(kicad_pcb
	(version 20260206)
	(generator "pcbnew")
	(generator_version "10.0")
	(general
		(thickness 1.6)
		(legacy_teardrops no)
	)
	(paper "A4")
	(title_block
		(title "12092022_DA0F0TMDCD0_F0T_Management_Board_D_brd_V3_OCP.brd")
		(comment 1 "Grand Teton / footprints 786-791 of 1440")
	)
	(layers
		(0 "F.Cu" signal "TOP")
		(4 "In1.Cu" signal "GND")
		(6 "In2.Cu" signal "IN1")
		(8 "In3.Cu" signal "GND1")
		(10 "In4.Cu" signal "IN2")
		(12 "In5.Cu" signal "VCC")
		(14 "In6.Cu" signal "VCC1")
		(16 "In7.Cu" signal "IN3")
		(18 "In8.Cu" signal "GND2")
		(20 "In9.Cu" signal "IN4")
		(22 "In10.Cu" signal "GND3")
		(2 "B.Cu" signal "BOTTOM")
		(9 "F.Adhes" user "F.Adhesive")
		(11 "B.Adhes" user "B.Adhesive")
		(13 "F.Paste" user "Package Geometry/Pastemask Top")
		(15 "B.Paste" user "Package Geometry/Pastemask Bottom")
		(5 "F.SilkS" user "Ref Des/Silkscreen Top")
		(7 "B.SilkS" user "Ref Des/Silkscreen Bottom")
		(1 "F.Mask" user "Board Geometry/Soldermask Top")
		(3 "B.Mask" user "Board Geometry/Soldermask Bottom")
		(17 "Dwgs.User" user "User.Drawings")
		(19 "Cmts.User" user "User.Comments")
		(21 "Eco1.User" user "User.Eco1")
		(23 "Eco2.User" user "User.Eco2")
		(25 "Edge.Cuts" user "Board Geometry/Outline")
		(27 "Margin" user)
		(31 "F.CrtYd" user "Package Geometry/Place Bound Top")
		(29 "B.CrtYd" user "Package Geometry/Place Bound Bottom")
		(35 "F.Fab" user "Ref Des/Assembly Top")
		(33 "B.Fab" user "Ref Des/Assembly Bottom")
	)
	(footprint ""
		(layer "B.Cu")
		(at 83.16722 -39.474394 180)
		(property "Reference" "R365"
			(at 0 0 0)
			(layer "B.SilkS")
			(hide yes)
			(effects
				(font
					(size 1.27 1.27)
				)
				(justify mirror)
			)
		)
		(property "Value" ""
			(at 0 0 0)
			(layer "B.Fab")
			(effects
				(font
					(size 1.27 1.27)
				)
				(justify mirror)
			)
		)
		(duplicate_pad_numbers_are_jumpers no)
		(fp_line
			(start 0.7874 0.4064)
			(end 0.7874 -0.4064)
			(stroke
				(width 0.1524)
				(type default)
			)
			(layer "B.SilkS")
		)
		(fp_line
			(start 0.7874 -0.4064)
			(end -0.7874 -0.4064)
			(stroke
				(width 0.1524)
				(type default)
			)
			(layer "B.SilkS")
		)
		(fp_line
			(start -0.7874 0.4064)
			(end 0.7874 0.4064)
			(stroke
				(width 0.1524)
				(type default)
			)
			(layer "B.SilkS")
		)
		(fp_line
			(start -0.7874 -0.4064)
			(end -0.7874 0.4064)
			(stroke
				(width 0.1524)
				(type default)
			)
			(layer "B.SilkS")
		)
		(fp_line
			(start 0.67945 0.3048)
			(end 0.67945 -0.305054)
			(stroke
				(width 0.1)
				(type default)
			)
			(layer "B.Fab")
		)
		(fp_line
			(start 0.67945 -0.305054)
			(end 0.12065 -0.305054)
			(stroke
				(width 0.1)
				(type default)
			)
			(layer "B.Fab")
		)
		(fp_line
			(start 0.12065 0.3048)
			(end 0.67945 0.3048)
			(stroke
				(width 0.1)
				(type default)
			)
			(layer "B.Fab")
		)
		(fp_line
			(start 0.12065 0.2794)
			(end 0.12065 0.3048)
			(stroke
				(width 0.1)
				(type default)
			)
			(layer "B.Fab")
		)
		(fp_line
			(start 0.12065 -0.2794)
			(end -0.12065 -0.2794)
			(stroke
				(width 0.1)
				(type default)
			)
			(layer "B.Fab")
		)
		(fp_line
			(start 0.12065 -0.305054)
			(end 0.12065 -0.2794)
			(stroke
				(width 0.1)
				(type default)
			)
			(layer "B.Fab")
		)
		(fp_line
			(start -0.120396 0.3048)
			(end -0.120396 0.2794)
			(stroke
				(width 0.1)
				(type default)
			)
			(layer "B.Fab")
		)
		(fp_line
			(start -0.120396 0.2794)
			(end 0.12065 0.2794)
			(stroke
				(width 0.1)
				(type default)
			)
			(layer "B.Fab")
		)
		(fp_line
			(start -0.12065 -0.2794)
			(end -0.12065 -0.3048)
			(stroke
				(width 0.1)
				(type default)
			)
			(layer "B.Fab")
		)
		(fp_line
			(start -0.12065 -0.3048)
			(end -0.67945 -0.3048)
			(stroke
				(width 0.1)
				(type default)
			)
			(layer "B.Fab")
		)
		(fp_line
			(start -0.67945 0.3048)
			(end -0.120396 0.3048)
			(stroke
				(width 0.1)
				(type default)
			)
			(layer "B.Fab")
		)
		(fp_line
			(start -0.67945 -0.3048)
			(end -0.67945 0.3048)
			(stroke
				(width 0.1)
				(type default)
			)
			(layer "B.Fab")
		)
		(pad "1" smd circle
			(at 0.40005 0)
			(size 0 0)
			(layers "B.Cu" "B.Mask" "B.Paste")
			(net "M_BMC_DDR4_MWE_N")
		)
		(pad "2" smd circle
			(at -0.40005 0)
			(size 0 0)
			(layers "B.Cu" "B.Mask" "B.Paste")
			(net "P1V2_AUX")
		)
	)
	(footprint ""
		(layer "B.Cu")
		(at 83.16722 -42.522394 180)
		(property "Reference" "R354"
			(at 0 0 0)
			(layer "B.SilkS")
			(hide yes)
			(effects
				(font
					(size 1.27 1.27)
				)
				(justify mirror)
			)
		)
		(property "Value" ""
			(at 0 0 0)
			(layer "B.Fab")
			(effects
				(font
					(size 1.27 1.27)
				)
				(justify mirror)
			)
		)
		(duplicate_pad_numbers_are_jumpers no)
		(fp_line
			(start 0.7874 0.4064)
			(end 0.7874 -0.4064)
			(stroke
				(width 0.1524)
				(type default)
			)
			(layer "B.SilkS")
		)
		(fp_line
			(start 0.7874 -0.4064)
			(end -0.7874 -0.4064)
			(stroke
				(width 0.1524)
				(type default)
			)
			(layer "B.SilkS")
		)
		(fp_line
			(start -0.7874 0.4064)
			(end 0.7874 0.4064)
			(stroke
				(width 0.1524)
				(type default)
			)
			(layer "B.SilkS")
		)
		(fp_line
			(start -0.7874 -0.4064)
			(end -0.7874 0.4064)
			(stroke
				(width 0.1524)
				(type default)
			)
			(layer "B.SilkS")
		)
		(fp_line
			(start 0.67945 0.3048)
			(end 0.67945 -0.305054)
			(stroke
				(width 0.1)
				(type default)
			)
			(layer "B.Fab")
		)
		(fp_line
			(start 0.67945 -0.305054)
			(end 0.12065 -0.305054)
			(stroke
				(width 0.1)
				(type default)
			)
			(layer "B.Fab")
		)
		(fp_line
			(start 0.12065 0.3048)
			(end 0.67945 0.3048)
			(stroke
				(width 0.1)
				(type default)
			)
			(layer "B.Fab")
		)
		(fp_line
			(start 0.12065 0.2794)
			(end 0.12065 0.3048)
			(stroke
				(width 0.1)
				(type default)
			)
			(layer "B.Fab")
		)
		(fp_line
			(start 0.12065 -0.2794)
			(end -0.12065 -0.2794)
			(stroke
				(width 0.1)
				(type default)
			)
			(layer "B.Fab")
		)
		(fp_line
			(start 0.12065 -0.305054)
			(end 0.12065 -0.2794)
			(stroke
				(width 0.1)
				(type default)
			)
			(layer "B.Fab")
		)
		(fp_line
			(start -0.120396 0.3048)
			(end -0.120396 0.2794)
			(stroke
				(width 0.1)
				(type default)
			)
			(layer "B.Fab")
		)
		(fp_line
			(start -0.120396 0.2794)
			(end 0.12065 0.2794)
			(stroke
				(width 0.1)
				(type default)
			)
			(layer "B.Fab")
		)
		(fp_line
			(start -0.12065 -0.2794)
			(end -0.12065 -0.3048)
			(stroke
				(width 0.1)
				(type default)
			)
			(layer "B.Fab")
		)
		(fp_line
			(start -0.12065 -0.3048)
			(end -0.67945 -0.3048)
			(stroke
				(width 0.1)
				(type default)
			)
			(layer "B.Fab")
		)
		(fp_line
			(start -0.67945 0.3048)
			(end -0.120396 0.3048)
			(stroke
				(width 0.1)
				(type default)
			)
			(layer "B.Fab")
		)
		(fp_line
			(start -0.67945 -0.3048)
			(end -0.67945 0.3048)
			(stroke
				(width 0.1)
				(type default)
			)
			(layer "B.Fab")
		)
		(pad "1" smd circle
			(at 0.40005 0)
			(size 0 0)
			(layers "B.Cu" "B.Mask" "B.Paste")
			(net "M_BMC_DDR4_MA<3>")
		)
		(pad "2" smd circle
			(at -0.40005 0)
			(size 0 0)
			(layers "B.Cu" "B.Mask" "B.Paste")
			(net "P1V2_AUX")
		)
	)
	(footprint ""
		(layer "B.Cu")
		(at 43.28922 -53.856382)
		(property "Reference" "C48"
			(at 0 0 0)
			(layer "B.SilkS")
			(hide yes)
			(effects
				(font
					(size 1.27 1.27)
				)
				(justify mirror)
			)
		)
		(property "Value" ""
			(at 0 0 0)
			(layer "B.Fab")
			(effects
				(font
					(size 1.27 1.27)
				)
				(justify mirror)
			)
		)
		(duplicate_pad_numbers_are_jumpers no)
		(fp_line
			(start -0.7874 -0.4064)
			(end -0.7874 0.4064)
			(stroke
				(width 0.1524)
				(type default)
			)
			(layer "B.SilkS")
		)
		(fp_line
			(start -0.7874 0.4064)
			(end 0.7874 0.4064)
			(stroke
				(width 0.1524)
				(type default)
			)
			(layer "B.SilkS")
		)
		(fp_line
			(start 0.7874 -0.4064)
			(end -0.7874 -0.4064)
			(stroke
				(width 0.1524)
				(type default)
			)
			(layer "B.SilkS")
		)
		(fp_line
			(start 0.7874 0.4064)
			(end 0.7874 -0.4064)
			(stroke
				(width 0.1524)
				(type default)
			)
			(layer "B.SilkS")
		)
		(fp_line
			(start -0.67945 -0.3048)
			(end -0.67945 0.3048)
			(stroke
				(width 0.1)
				(type default)
			)
			(layer "B.Fab")
		)
		(fp_line
			(start -0.67945 0.3048)
			(end -0.120396 0.3048)
			(stroke
				(width 0.1)
				(type default)
			)
			(layer "B.Fab")
		)
		(fp_line
			(start -0.12065 -0.3048)
			(end -0.67945 -0.3048)
			(stroke
				(width 0.1)
				(type default)
			)
			(layer "B.Fab")
		)
		(fp_line
			(start -0.12065 -0.2794)
			(end -0.12065 -0.3048)
			(stroke
				(width 0.1)
				(type default)
			)
			(layer "B.Fab")
		)
		(fp_line
			(start -0.120396 0.2794)
			(end 0.12065 0.2794)
			(stroke
				(width 0.1)
				(type default)
			)
			(layer "B.Fab")
		)
		(fp_line
			(start -0.120396 0.3048)
			(end -0.120396 0.2794)
			(stroke
				(width 0.1)
				(type default)
			)
			(layer "B.Fab")
		)
		(fp_line
			(start 0.12065 -0.305054)
			(end 0.12065 -0.2794)
			(stroke
				(width 0.1)
				(type default)
			)
			(layer "B.Fab")
		)
		(fp_line
			(start 0.12065 -0.2794)
			(end -0.12065 -0.2794)
			(stroke
				(width 0.1)
				(type default)
			)
			(layer "B.Fab")
		)
		(fp_line
			(start 0.12065 0.2794)
			(end 0.12065 0.3048)
			(stroke
				(width 0.1)
				(type default)
			)
			(layer "B.Fab")
		)
		(fp_line
			(start 0.12065 0.3048)
			(end 0.67945 0.3048)
			(stroke
				(width 0.1)
				(type default)
			)
			(layer "B.Fab")
		)
		(fp_line
			(start 0.67945 -0.305054)
			(end 0.12065 -0.305054)
			(stroke
				(width 0.1)
				(type default)
			)
			(layer "B.Fab")
		)
		(fp_line
			(start 0.67945 0.3048)
			(end 0.67945 -0.305054)
			(stroke
				(width 0.1)
				(type default)
			)
			(layer "B.Fab")
		)
		(pad "1" smd circle
			(at 0.40005 0 180)
			(size 0 0)
			(layers "B.Cu" "B.Mask" "B.Paste")
			(net "P3V3_STBY_DACAV33")
		)
		(pad "2" smd circle
			(at -0.40005 0 180)
			(size 0 0)
			(layers "B.Cu" "B.Mask" "B.Paste")
			(net "GND")
		)
	)
	(footprint ""
		(layer "B.Cu")
		(at 16.764 -72.771 -90)
		(property "Reference" "R302"
			(at 0 0 90)
			(layer "B.SilkS")
			(hide yes)
			(effects
				(font
					(size 1.27 1.27)
				)
				(justify mirror)
			)
		)
		(property "Value" ""
			(at 0 0 90)
			(layer "B.Fab")
			(effects
				(font
					(size 1.27 1.27)
				)
				(justify mirror)
			)
		)
		(duplicate_pad_numbers_are_jumpers no)
		(fp_line
			(start -0.7874 0.4064)
			(end 0.7874 0.4064)
			(stroke
				(width 0.1524)
				(type default)
			)
			(layer "B.SilkS")
		)
		(fp_line
			(start 0.7874 0.4064)
			(end 0.7874 -0.4064)
			(stroke
				(width 0.1524)
				(type default)
			)
			(layer "B.SilkS")
		)
		(fp_line
			(start -0.7874 -0.4064)
			(end -0.7874 0.4064)
			(stroke
				(width 0.1524)
				(type default)
			)
			(layer "B.SilkS")
		)
		(fp_line
			(start 0.7874 -0.4064)
			(end -0.7874 -0.4064)
			(stroke
				(width 0.1524)
				(type default)
			)
			(layer "B.SilkS")
		)
		(fp_line
			(start -0.67945 0.3048)
			(end -0.120396 0.3048)
			(stroke
				(width 0.1)
				(type default)
			)
			(layer "B.Fab")
		)
		(fp_line
			(start -0.120396 0.3048)
			(end -0.120396 0.2794)
			(stroke
				(width 0.1)
				(type default)
			)
			(layer "B.Fab")
		)
		(fp_line
			(start 0.12065 0.3048)
			(end 0.67945 0.3048)
			(stroke
				(width 0.1)
				(type default)
			)
			(layer "B.Fab")
		)
		(fp_line
			(start 0.67945 0.3048)
			(end 0.67945 -0.305054)
			(stroke
				(width 0.1)
				(type default)
			)
			(layer "B.Fab")
		)
		(fp_line
			(start -0.120396 0.2794)
			(end 0.12065 0.2794)
			(stroke
				(width 0.1)
				(type default)
			)
			(layer "B.Fab")
		)
		(fp_line
			(start 0.12065 0.2794)
			(end 0.12065 0.3048)
			(stroke
				(width 0.1)
				(type default)
			)
			(layer "B.Fab")
		)
		(fp_line
			(start -0.12065 -0.2794)
			(end -0.12065 -0.3048)
			(stroke
				(width 0.1)
				(type default)
			)
			(layer "B.Fab")
		)
		(fp_line
			(start 0.12065 -0.2794)
			(end -0.12065 -0.2794)
			(stroke
				(width 0.1)
				(type default)
			)
			(layer "B.Fab")
		)
		(fp_line
			(start -0.67945 -0.3048)
			(end -0.67945 0.3048)
			(stroke
				(width 0.1)
				(type default)
			)
			(layer "B.Fab")
		)
		(fp_line
			(start -0.12065 -0.3048)
			(end -0.67945 -0.3048)
			(stroke
				(width 0.1)
				(type default)
			)
			(layer "B.Fab")
		)
		(fp_line
			(start 0.12065 -0.305054)
			(end 0.12065 -0.2794)
			(stroke
				(width 0.1)
				(type default)
			)
			(layer "B.Fab")
		)
		(fp_line
			(start 0.67945 -0.305054)
			(end 0.12065 -0.305054)
			(stroke
				(width 0.1)
				(type default)
			)
			(layer "B.Fab")
		)
		(pad "1" smd circle
			(at 0.40005 0 90)
			(size 0 0)
			(layers "B.Cu" "B.Mask" "B.Paste")
			(net "SMB_DEBUG_AUX_LVC3_USB_R1_SDA")
		)
		(pad "2" smd circle
			(at -0.40005 0 90)
			(size 0 0)
			(layers "B.Cu" "B.Mask" "B.Paste")
			(net "SMB_DEBUG_AUX_LVC3_USB_SDA")
		)
	)
	(footprint ""
		(layer "B.Cu")
		(at 72.758808 -37.271706 -90)
		(property "Reference" "C62"
			(at 0 0 90)
			(layer "B.SilkS")
			(hide yes)
			(effects
				(font
					(size 1.27 1.27)
				)
				(justify mirror)
			)
		)
		(property "Value" ""
			(at 0 0 90)
			(layer "B.Fab")
			(effects
				(font
					(size 1.27 1.27)
				)
				(justify mirror)
			)
		)
		(duplicate_pad_numbers_are_jumpers no)
		(fp_line
			(start -0.7874 0.4064)
			(end 0.7874 0.4064)
			(stroke
				(width 0.1524)
				(type default)
			)
			(layer "B.SilkS")
		)
		(fp_line
			(start 0.7874 0.4064)
			(end 0.7874 -0.4064)
			(stroke
				(width 0.1524)
				(type default)
			)
			(layer "B.SilkS")
		)
		(fp_line
			(start -0.7874 -0.4064)
			(end -0.7874 0.4064)
			(stroke
				(width 0.1524)
				(type default)
			)
			(layer "B.SilkS")
		)
		(fp_line
			(start 0.7874 -0.4064)
			(end -0.7874 -0.4064)
			(stroke
				(width 0.1524)
				(type default)
			)
			(layer "B.SilkS")
		)
		(fp_line
			(start -0.67945 0.3048)
			(end -0.120396 0.3048)
			(stroke
				(width 0.1)
				(type default)
			)
			(layer "B.Fab")
		)
		(fp_line
			(start -0.120396 0.3048)
			(end -0.120396 0.2794)
			(stroke
				(width 0.1)
				(type default)
			)
			(layer "B.Fab")
		)
		(fp_line
			(start 0.12065 0.3048)
			(end 0.67945 0.3048)
			(stroke
				(width 0.1)
				(type default)
			)
			(layer "B.Fab")
		)
		(fp_line
			(start 0.67945 0.3048)
			(end 0.67945 -0.305054)
			(stroke
				(width 0.1)
				(type default)
			)
			(layer "B.Fab")
		)
		(fp_line
			(start -0.120396 0.2794)
			(end 0.12065 0.2794)
			(stroke
				(width 0.1)
				(type default)
			)
			(layer "B.Fab")
		)
		(fp_line
			(start 0.12065 0.2794)
			(end 0.12065 0.3048)
			(stroke
				(width 0.1)
				(type default)
			)
			(layer "B.Fab")
		)
		(fp_line
			(start -0.12065 -0.2794)
			(end -0.12065 -0.3048)
			(stroke
				(width 0.1)
				(type default)
			)
			(layer "B.Fab")
		)
		(fp_line
			(start 0.12065 -0.2794)
			(end -0.12065 -0.2794)
			(stroke
				(width 0.1)
				(type default)
			)
			(layer "B.Fab")
		)
		(fp_line
			(start -0.67945 -0.3048)
			(end -0.67945 0.3048)
			(stroke
				(width 0.1)
				(type default)
			)
			(layer "B.Fab")
		)
		(fp_line
			(start -0.12065 -0.3048)
			(end -0.67945 -0.3048)
			(stroke
				(width 0.1)
				(type default)
			)
			(layer "B.Fab")
		)
		(fp_line
			(start 0.12065 -0.305054)
			(end 0.12065 -0.2794)
			(stroke
				(width 0.1)
				(type default)
			)
			(layer "B.Fab")
		)
		(fp_line
			(start 0.67945 -0.305054)
			(end 0.12065 -0.305054)
			(stroke
				(width 0.1)
				(type default)
			)
			(layer "B.Fab")
		)
		(pad "1" smd circle
			(at 0.40005 0 90)
			(size 0 0)
			(layers "B.Cu" "B.Mask" "B.Paste")
			(net "P1V2_AUX")
		)
		(pad "2" smd circle
			(at -0.40005 0 90)
			(size 0 0)
			(layers "B.Cu" "B.Mask" "B.Paste")
			(net "GND")
		)
	)
	(footprint ""
		(layer "B.Cu")
		(at 32.396684 -58.349388 -90)
		(property "Reference" "R785"
			(at 0 0 90)
			(layer "B.SilkS")
			(hide yes)
			(effects
				(font
					(size 1.27 1.27)
				)
				(justify mirror)
			)
		)
		(property "Value" ""
			(at 0 0 90)
			(layer "B.Fab")
			(effects
				(font
					(size 1.27 1.27)
				)
				(justify mirror)
			)
		)
		(duplicate_pad_numbers_are_jumpers no)
		(fp_line
			(start -0.7874 0.4064)
			(end 0.7874 0.4064)
			(stroke
				(width 0.1524)
				(type default)
			)
			(layer "B.SilkS")
		)
		(fp_line
			(start 0.7874 0.4064)
			(end 0.7874 -0.4064)
			(stroke
				(width 0.1524)
				(type default)
			)
			(layer "B.SilkS")
		)
		(fp_line
			(start -0.7874 -0.4064)
			(end -0.7874 0.4064)
			(stroke
				(width 0.1524)
				(type default)
			)
			(layer "B.SilkS")
		)
		(fp_line
			(start 0.7874 -0.4064)
			(end -0.7874 -0.4064)
			(stroke
				(width 0.1524)
				(type default)
			)
			(layer "B.SilkS")
		)
		(fp_line
			(start -0.67945 0.3048)
			(end -0.120396 0.3048)
			(stroke
				(width 0.1)
				(type default)
			)
			(layer "B.Fab")
		)
		(fp_line
			(start -0.120396 0.3048)
			(end -0.120396 0.2794)
			(stroke
				(width 0.1)
				(type default)
			)
			(layer "B.Fab")
		)
		(fp_line
			(start 0.12065 0.3048)
			(end 0.67945 0.3048)
			(stroke
				(width 0.1)
				(type default)
			)
			(layer "B.Fab")
		)
		(fp_line
			(start 0.67945 0.3048)
			(end 0.67945 -0.305054)
			(stroke
				(width 0.1)
				(type default)
			)
			(layer "B.Fab")
		)
		(fp_line
			(start -0.120396 0.2794)
			(end 0.12065 0.2794)
			(stroke
				(width 0.1)
				(type default)
			)
			(layer "B.Fab")
		)
		(fp_line
			(start 0.12065 0.2794)
			(end 0.12065 0.3048)
			(stroke
				(width 0.1)
				(type default)
			)
			(layer "B.Fab")
		)
		(fp_line
			(start -0.12065 -0.2794)
			(end -0.12065 -0.3048)
			(stroke
				(width 0.1)
				(type default)
			)
			(layer "B.Fab")
		)
		(fp_line
			(start 0.12065 -0.2794)
			(end -0.12065 -0.2794)
			(stroke
				(width 0.1)
				(type default)
			)
			(layer "B.Fab")
		)
		(fp_line
			(start -0.67945 -0.3048)
			(end -0.67945 0.3048)
			(stroke
				(width 0.1)
				(type default)
			)
			(layer "B.Fab")
		)
		(fp_line
			(start -0.12065 -0.3048)
			(end -0.67945 -0.3048)
			(stroke
				(width 0.1)
				(type default)
			)
			(layer "B.Fab")
		)
		(fp_line
			(start 0.12065 -0.305054)
			(end 0.12065 -0.2794)
			(stroke
				(width 0.1)
				(type default)
			)
			(layer "B.Fab")
		)
		(fp_line
			(start 0.67945 -0.305054)
			(end 0.12065 -0.305054)
			(stroke
				(width 0.1)
				(type default)
			)
			(layer "B.Fab")
		)
		(pad "1" smd circle
			(at 0.40005 0 90)
			(size 0 0)
			(layers "B.Cu" "B.Mask" "B.Paste")
			(net "P12V_AUX")
		)
		(pad "2" smd circle
			(at -0.40005 0 90)
			(size 0 0)
			(layers "B.Cu" "B.Mask" "B.Paste")
			(net "P12V_SENSOR")
		)
	)
)
